# S9S_MB_2U (Grand Teton) — schematic netlist excerpt (pin names and nets, part order shuffled) for the footprints in the layout excerpt that follows; sources: Cadence DE-HDL packaged netlist, KiCad conversion of 03242023_DA0F0TMBIJ0_F0T_Motherboard_J_brd_V01_OCP.brd

R1230  Q_RES  240 1% EMPTY  pkg 0402LF  page 119 : A = PVNN_TERM_CPU1 ; B = PUD_XTAL_CPU1_MODE1
R22  Q_RES  100 1% CHIP  pkg 0402LF  page 16 : A = DBP_CPU0_MBP0_GTL_R_N ; B = DBP_CPU_MBP0_GTL_N

(kicad_pcb
	(version 20260206)
	(generator "pcbnew")
	(generator_version "10.0")
	(general
		(thickness 1.6)
		(legacy_teardrops no)
	)
	(paper "A4")
	(title_block
		(title "03242023_DA0F0TMBIJ0_F0T_Motherboard_J_brd_V01_OCP.brd")
		(comment 1 "Grand Teton / footprints 5643-5644 of 6105")
	)
	(layers
		(0 "F.Cu" signal "TOP")
		(4 "In1.Cu" signal "GND")
		(6 "In2.Cu" signal "IN1")
		(8 "In3.Cu" signal "GND1")
		(10 "In4.Cu" signal "IN2")
		(12 "In5.Cu" signal "GND2")
		(14 "In6.Cu" signal "IN3")
		(16 "In7.Cu" signal "GND3")
		(18 "In8.Cu" signal "VCC")
		(20 "In9.Cu" signal "VCC1")
		(22 "In10.Cu" signal "GND4")
		(24 "In11.Cu" signal "IN4")
		(26 "In12.Cu" signal "GND5")
		(28 "In13.Cu" signal "IN5")
		(30 "In14.Cu" signal "GND6")
		(32 "In15.Cu" signal "IN6")
		(34 "In16.Cu" signal "GND7")
		(2 "B.Cu" signal "BOTTOM")
		(9 "F.Adhes" user "F.Adhesive")
		(11 "B.Adhes" user "B.Adhesive")
		(13 "F.Paste" user "Package Geometry/Pastemask Top")
		(15 "B.Paste" user "Package Geometry/Pastemask Bottom")
		(5 "F.SilkS" user "Ref Des/Silkscreen Top")
		(7 "B.SilkS" user "Ref Des/Silkscreen Bottom")
		(1 "F.Mask" user "Board Geometry/Soldermask Top")
		(3 "B.Mask" user "Board Geometry/Soldermask Bottom")
		(17 "Dwgs.User" user "User.Drawings")
		(19 "Cmts.User" user "User.Comments")
		(21 "Eco1.User" user "User.Eco1")
		(23 "Eco2.User" user "User.Eco2")
		(25 "Edge.Cuts" user "Board Geometry/Outline")
		(27 "Margin" user)
		(31 "F.CrtYd" user "Package Geometry/Place Bound Top")
		(29 "B.CrtYd" user "Package Geometry/Place Bound Bottom")
		(35 "F.Fab" user "Ref Des/Assembly Top")
		(33 "B.Fab" user "Ref Des/Assembly Bottom")
	)
	(footprint ""
		(layer "B.Cu")
		(at 166.386002 -251.267214 180)
		(property "Reference" "R1230"
			(at 0 0 0)
			(layer "B.SilkS")
			(hide yes)
			(effects
				(font
					(size 1.27 1.27)
				)
				(justify mirror)
			)
		)
		(property "Value" ""
			(at 0 0 0)
			(layer "B.Fab")
			(effects
				(font
					(size 1.27 1.27)
				)
				(justify mirror)
			)
		)
		(duplicate_pad_numbers_are_jumpers no)
		(fp_line
			(start 0.7874 0.4064)
			(end 0.7874 -0.4064)
			(stroke
				(width 0.1524)
				(type default)
			)
			(layer "B.SilkS")
		)
		(fp_line
			(start 0.7874 -0.4064)
			(end -0.7874 -0.4064)
			(stroke
				(width 0.1524)
				(type default)
			)
			(layer "B.SilkS")
		)
		(fp_line
			(start -0.7874 0.4064)
			(end 0.7874 0.4064)
			(stroke
				(width 0.1524)
				(type default)
			)
			(layer "B.SilkS")
		)
		(fp_line
			(start -0.7874 -0.4064)
			(end -0.7874 0.4064)
			(stroke
				(width 0.1524)
				(type default)
			)
			(layer "B.SilkS")
		)
		(fp_line
			(start 0.67945 0.3048)
			(end 0.67945 -0.305054)
			(stroke
				(width 0.1)
				(type default)
			)
			(layer "B.Fab")
		)
		(fp_line
			(start 0.67945 -0.305054)
			(end 0.12065 -0.305054)
			(stroke
				(width 0.1)
				(type default)
			)
			(layer "B.Fab")
		)
		(fp_line
			(start 0.12065 0.3048)
			(end 0.67945 0.3048)
			(stroke
				(width 0.1)
				(type default)
			)
			(layer "B.Fab")
		)
		(fp_line
			(start 0.12065 0.2794)
			(end 0.12065 0.3048)
			(stroke
				(width 0.1)
				(type default)
			)
			(layer "B.Fab")
		)
		(fp_line
			(start 0.12065 -0.2794)
			(end -0.12065 -0.2794)
			(stroke
				(width 0.1)
				(type default)
			)
			(layer "B.Fab")
		)
		(fp_line
			(start 0.12065 -0.305054)
			(end 0.12065 -0.2794)
			(stroke
				(width 0.1)
				(type default)
			)
			(layer "B.Fab")
		)
		(fp_line
			(start -0.120396 0.3048)
			(end -0.120396 0.2794)
			(stroke
				(width 0.1)
				(type default)
			)
			(layer "B.Fab")
		)
		(fp_line
			(start -0.120396 0.2794)
			(end 0.12065 0.2794)
			(stroke
				(width 0.1)
				(type default)
			)
			(layer "B.Fab")
		)
		(fp_line
			(start -0.12065 -0.2794)
			(end -0.12065 -0.3048)
			(stroke
				(width 0.1)
				(type default)
			)
			(layer "B.Fab")
		)
		(fp_line
			(start -0.12065 -0.3048)
			(end -0.67945 -0.3048)
			(stroke
				(width 0.1)
				(type default)
			)
			(layer "B.Fab")
		)
		(fp_line
			(start -0.67945 0.3048)
			(end -0.120396 0.3048)
			(stroke
				(width 0.1)
				(type default)
			)
			(layer "B.Fab")
		)
		(fp_line
			(start -0.67945 -0.3048)
			(end -0.67945 0.3048)
			(stroke
				(width 0.1)
				(type default)
			)
			(layer "B.Fab")
		)
		(pad "1" smd circle
			(at 0.40005 0)
			(size 0 0)
			(layers "B.Cu" "B.Mask" "B.Paste")
			(net "PVNN_TERM_CPU1")
		)
		(pad "2" smd circle
			(at -0.40005 0)
			(size 0 0)
			(layers "B.Cu" "B.Mask" "B.Paste")
			(net "PUD_XTAL_CPU1_MODE1")
		)
	)
	(footprint ""
		(layer "B.Cu")
		(at 334.341978 -190.82893 90)
		(property "Reference" "R22"
			(at 0 0 90)
			(layer "B.SilkS")
			(hide yes)
			(effects
				(font
					(size 1.27 1.27)
				)
				(justify mirror)
			)
		)
		(property "Value" ""
			(at 0 0 90)
			(layer "B.Fab")
			(effects
				(font
					(size 1.27 1.27)
				)
				(justify mirror)
			)
		)
		(duplicate_pad_numbers_are_jumpers no)
		(fp_line
			(start 0.7874 -0.4064)
			(end -0.7874 -0.4064)
			(stroke
				(width 0.1524)
				(type default)
			)
			(layer "B.SilkS")
		)
		(fp_line
			(start -0.7874 -0.4064)
			(end -0.7874 0.4064)
			(stroke
				(width 0.1524)
				(type default)
			)
			(layer "B.SilkS")
		)
		(fp_line
			(start 0.7874 0.4064)
			(end 0.7874 -0.4064)
			(stroke
				(width 0.1524)
				(type default)
			)
			(layer "B.SilkS")
		)
		(fp_line
			(start -0.7874 0.4064)
			(end 0.7874 0.4064)
			(stroke
				(width 0.1524)
				(type default)
			)
			(layer "B.SilkS")
		)
		(fp_line
			(start 0.67945 -0.305054)
			(end 0.12065 -0.305054)
			(stroke
				(width 0.1)
				(type default)
			)
			(layer "B.Fab")
		)
		(fp_line
			(start 0.12065 -0.305054)
			(end 0.12065 -0.2794)
			(stroke
				(width 0.1)
				(type default)
			)
			(layer "B.Fab")
		)
		(fp_line
			(start -0.12065 -0.3048)
			(end -0.67945 -0.3048)
			(stroke
				(width 0.1)
				(type default)
			)
			(layer "B.Fab")
		)
		(fp_line
			(start -0.67945 -0.3048)
			(end -0.67945 0.3048)
			(stroke
				(width 0.1)
				(type default)
			)
			(layer "B.Fab")
		)
		(fp_line
			(start 0.12065 -0.2794)
			(end -0.12065 -0.2794)
			(stroke
				(width 0.1)
				(type default)
			)
			(layer "B.Fab")
		)
		(fp_line
			(start -0.12065 -0.2794)
			(end -0.12065 -0.3048)
			(stroke
				(width 0.1)
				(type default)
			)
			(layer "B.Fab")
		)
		(fp_line
			(start 0.12065 0.2794)
			(end 0.12065 0.3048)
			(stroke
				(width 0.1)
				(type default)
			)
			(layer "B.Fab")
		)
		(fp_line
			(start -0.120396 0.2794)
			(end 0.12065 0.2794)
			(stroke
				(width 0.1)
				(type default)
			)
			(layer "B.Fab")
		)
		(fp_line
			(start 0.67945 0.3048)
			(end 0.67945 -0.305054)
			(stroke
				(width 0.1)
				(type default)
			)
			(layer "B.Fab")
		)
		(fp_line
			(start 0.12065 0.3048)
			(end 0.67945 0.3048)
			(stroke
				(width 0.1)
				(type default)
			)
			(layer "B.Fab")
		)
		(fp_line
			(start -0.120396 0.3048)
			(end -0.120396 0.2794)
			(stroke
				(width 0.1)
				(type default)
			)
			(layer "B.Fab")
		)
		(fp_line
			(start -0.67945 0.3048)
			(end -0.120396 0.3048)
			(stroke
				(width 0.1)
				(type default)
			)
			(layer "B.Fab")
		)
		(pad "1" smd circle
			(at 0.40005 0 270)
			(size 0 0)
			(layers "B.Cu" "B.Mask" "B.Paste")
			(net "DBP_CPU0_MBP0_GTL_R_N")
		)
		(pad "2" smd circle
			(at -0.40005 0 270)
			(size 0 0)
			(layers "B.Cu" "B.Mask" "B.Paste")
			(net "DBP_CPU_MBP0_GTL_N")
		)
	)
)
